(kicad_pcb
	(version 20260206)
	(generator "pcbnew")
	(generator_version "10.0")
	(general
		(thickness 1.6)
		(legacy_teardrops no)
	)
	(paper "A4")
	(title_block
		(title "04192023_DAF0TMB3IC0_F0TG_MB_C_brd_V02_OCP.brd")
		(comment 1 "Grand Teton / footprints 4277-4278 of 8354")
	)
	(layers
		(0 "F.Cu" signal "TOP")
		(4 "In1.Cu" signal "GND")
		(6 "In2.Cu" signal "IN1")
		(8 "In3.Cu" signal "GND1")
		(10 "In4.Cu" signal "IN2")
		(12 "In5.Cu" signal "GND2")
		(14 "In6.Cu" signal "IN3")
		(16 "In7.Cu" signal "GND3")
		(18 "In8.Cu" signal "VCC")
		(20 "In9.Cu" signal "VCC1")
		(22 "In10.Cu" signal "GND4")
		(24 "In11.Cu" signal "IN4")
		(26 "In12.Cu" signal "GND5")
		(28 "In13.Cu" signal "IN5")
		(30 "In14.Cu" signal "GND6")
		(32 "In15.Cu" signal "IN6")
		(34 "In16.Cu" signal "GND7")
		(2 "B.Cu" signal "BOTTOM")
		(9 "F.Adhes" user "F.Adhesive")
		(11 "B.Adhes" user "B.Adhesive")
		(13 "F.Paste" user "Package Geometry/Pastemask Top")
		(15 "B.Paste" user "Package Geometry/Pastemask Bottom")
		(5 "F.SilkS" user "Ref Des/Silkscreen Top")
		(7 "B.SilkS" user "Ref Des/Silkscreen Bottom")
		(1 "F.Mask" user "Board Geometry/Soldermask Top")
		(3 "B.Mask" user "Board Geometry/Soldermask Bottom")
		(17 "Dwgs.User" user "User.Drawings")
		(19 "Cmts.User" user "User.Comments")
		(21 "Eco1.User" user "User.Eco1")
		(23 "Eco2.User" user "User.Eco2")
		(25 "Edge.Cuts" user "Board Geometry/Outline")
		(27 "Margin" user)
		(31 "F.CrtYd" user "Package Geometry/Place Bound Top")
		(29 "B.CrtYd" user "Package Geometry/Place Bound Bottom")
		(35 "F.Fab" user "Ref Des/Assembly Top")
		(33 "B.Fab" user "Ref Des/Assembly Bottom")
	)
	(footprint ""
		(layer "F.Cu")
		(at 418.917882 -362.087414 -90)
		(property "Reference" "PU21"
			(at -5.639816 -0.501904 0)
			(unlocked yes)
			(layer "F.SilkS")
			(effects
				(font
					(size 0.7874 0.5842)
					(thickness 0.1524)
				)
				(justify left)
			)
		)
		(property "Value" ""
			(at 0 0 270)
			(layer "F.Fab")
			(effects
				(font
					(size 1.27 1.27)
				)
			)
		)
		(duplicate_pad_numbers_are_jumpers no)
		(fp_line
			(start 1.778 3.6322)
			(end 1.778 2.8702)
			(stroke
				(width 0.1524)
				(type default)
			)
			(layer "F.SilkS")
		)
		(fp_line
			(start -0.2032 2.8829)
			(end -0.2032 3.2639)
			(stroke
				(width 0.1524)
				(type default)
			)
			(layer "F.SilkS")
		)
		(fp_line
			(start -2.500122 2.500122)
			(end -2.500122 2.018538)
			(stroke
				(width 0.1524)
				(type default)
			)
			(layer "F.SilkS")
		)
		(fp_line
			(start -2.015998 2.500122)
			(end -2.500122 2.500122)
			(stroke
				(width 0.1524)
				(type default)
			)
			(layer "F.SilkS")
		)
		(fp_line
			(start 2.500122 2.500122)
			(end 2.015998 2.500122)
			(stroke
				(width 0.1524)
				(type default)
			)
			(layer "F.SilkS")
		)
		(fp_line
			(start 2.500122 2.015998)
			(end 2.500122 2.500122)
			(stroke
				(width 0.1524)
				(type default)
			)
			(layer "F.SilkS")
		)
		(fp_line
			(start -3.103626 1.8034)
			(end -2.8956 1.8034)
			(stroke
				(width 0.1524)
				(type default)
			)
			(layer "F.SilkS")
		)
		(fp_line
			(start 2.8829 0.2032)
			(end 3.2639 0.2032)
			(stroke
				(width 0.1524)
				(type default)
			)
			(layer "F.SilkS")
		)
		(fp_line
			(start -3.2639 -0.1778)
			(end -2.8829 -0.1778)
			(stroke
				(width 0.1524)
				(type default)
			)
			(layer "F.SilkS")
		)
		(fp_line
			(start 2.8702 -1.778)
			(end 3.6322 -1.778)
			(stroke
				(width 0.1524)
				(type default)
			)
			(layer "F.SilkS")
		)
		(fp_line
			(start -2.500122 -2.015998)
			(end -2.500122 -2.500122)
			(stroke
				(width 0.1524)
				(type default)
			)
			(layer "F.SilkS")
		)
		(fp_line
			(start -2.500122 -2.500122)
			(end -2.015998 -2.500122)
			(stroke
				(width 0.1524)
				(type default)
			)
			(layer "F.SilkS")
		)
		(fp_line
			(start 2.015998 -2.500122)
			(end 2.500122 -2.500122)
			(stroke
				(width 0.1524)
				(type default)
			)
			(layer "F.SilkS")
		)
		(fp_line
			(start 2.500122 -2.500122)
			(end 2.500122 -2.015998)
			(stroke
				(width 0.1524)
				(type default)
			)
			(layer "F.SilkS")
		)
		(fp_line
			(start -1.8034 -2.8702)
			(end -1.8034 -3.6322)
			(stroke
				(width 0.1524)
				(type default)
			)
			(layer "F.SilkS")
		)
		(fp_line
			(start 0.1778 -3.2385)
			(end 0.1778 -2.8575)
			(stroke
				(width 0.1524)
				(type default)
			)
			(layer "F.SilkS")
		)
		(fp_poly
			(pts
				(xy -2.391918 -2.826512) (xy -2.622296 -2.366264) (xy -2.852674 -2.826766)
			)
			(stroke
				(width 0)
				(type default)
			)
			(fill yes)
			(layer "F.SilkS")
		)
		(fp_line
			(start 1.778 3.6322)
			(end 1.778 2.8702)
			(stroke
				(width 0.1)
				(type default)
			)
			(layer "F.Fab")
		)
		(fp_line
			(start -0.2032 2.8829)
			(end -0.2032 3.2639)
			(stroke
				(width 0.1)
				(type default)
			)
			(layer "F.Fab")
		)
		(fp_line
			(start -2.500122 2.500122)
			(end -2.500122 -2.500122)
			(stroke
				(width 0.1)
				(type default)
			)
			(layer "F.Fab")
		)
		(fp_line
			(start 2.500122 2.500122)
			(end -2.500122 2.500122)
			(stroke
				(width 0.1)
				(type default)
			)
			(layer "F.Fab")
		)
		(fp_line
			(start -3.6576 1.8034)
			(end -2.8956 1.8034)
			(stroke
				(width 0.1)
				(type default)
			)
			(layer "F.Fab")
		)
		(fp_line
			(start 2.8829 0.2032)
			(end 3.2639 0.2032)
			(stroke
				(width 0.1)
				(type default)
			)
			(layer "F.Fab")
		)
		(fp_line
			(start -3.2639 -0.1778)
			(end -2.8829 -0.1778)
			(stroke
				(width 0.1)
				(type default)
			)
			(layer "F.Fab")
		)
		(fp_line
			(start 2.8702 -1.778)
			(end 3.6322 -1.778)
			(stroke
				(width 0.1)
				(type default)
			)
			(layer "F.Fab")
		)
		(fp_line
			(start -2.500122 -2.500122)
			(end 2.500122 -2.500122)
			(stroke
				(width 0.1)
				(type default)
			)
			(layer "F.Fab")
		)
		(fp_line
			(start 2.500122 -2.500122)
			(end 2.500122 2.500122)
			(stroke
				(width 0.1)
				(type default)
			)
			(layer "F.Fab")
		)
		(fp_line
			(start -1.8034 -2.8702)
			(end -1.8034 -3.6322)
			(stroke
				(width 0.1)
				(type default)
			)
			(layer "F.Fab")
		)
		(fp_line
			(start 0.1778 -3.2385)
			(end 0.1778 -2.8575)
			(stroke
				(width 0.1)
				(type default)
			)
			(layer "F.Fab")
		)
		(fp_poly
			(pts
				(xy -2.921 -1.800098) (xy -3.504184 -1.508506) (xy -3.504184 -2.09169)
			)
			(stroke
				(width 0)
				(type default)
			)
			(fill yes)
			(layer "F.Fab")
		)
		(fp_text user "20"
			(at 1.8288 5.031232 270)
			(unlocked yes)
			(layer "F.SilkS")
			(effects
				(font
					(size 0.635 0.4064)
					(thickness 0.1524)
				)
				(justify left)
			)
		)
		(fp_text user "21"
			(at 4.1021 4.501642 180)
			(unlocked yes)
			(layer "F.SilkS")
			(effects
				(font
					(size 0.635 0.4064)
					(thickness 0.1524)
				)
				(justify left)
			)
		)
		(fp_text user "11"
			(at -2.8702 3.278632 270)
			(unlocked yes)
			(layer "F.SilkS")
			(effects
				(font
					(size 0.635 0.4064)
					(thickness 0.1524)
				)
				(justify left)
			)
		)
		(fp_text user "10"
			(at -3.395726 1.796288 180)
			(unlocked yes)
			(layer "F.SilkS")
			(effects
				(font
					(size 0.635 0.4064)
					(thickness 0.1524)
				)
				(justify left)
			)
		)
		(fp_text user "30"
			(at 3.096768 -2.9718 180)
			(unlocked yes)
			(layer "F.SilkS")
			(effects
				(font
					(size 0.635 0.4064)
					(thickness 0.1524)
				)
				(justify left)
			)
		)
		(fp_text user "31"
			(at 0.98298 -3.172968 270)
			(unlocked yes)
			(layer "F.SilkS")
			(effects
				(font
					(size 0.635 0.4064)
					(thickness 0.1524)
				)
				(justify left)
			)
		)
		(fp_text user "40"
			(at -2.6924 -6.017768 270)
			(unlocked yes)
			(layer "F.SilkS")
			(effects
				(font
					(size 0.635 0.4064)
					(thickness 0.1524)
				)
				(justify left)
			)
		)
		(fp_text user "11"
			(at -2.8702 3.278632 270)
			(unlocked yes)
			(layer "F.Fab")
			(effects
				(font
					(size 0.635 0.4064)
					(thickness 0.1524)
				)
				(justify left)
			)
		)
		(fp_text user "20"
			(at 2.0828 3.253232 270)
			(unlocked yes)
			(layer "F.Fab")
			(effects
				(font
					(size 0.635 0.4064)
					(thickness 0.1524)
				)
				(justify left)
			)
		)
		(fp_text user "10"
			(at -3.253232 2.1336 180)
			(unlocked yes)
			(layer "F.Fab")
			(effects
				(font
					(size 0.635 0.4064)
					(thickness 0.1524)
				)
				(justify left)
			)
		)
		(fp_text user "21"
			(at 3.274568 1.8796 180)
			(unlocked yes)
			(layer "F.Fab")
			(effects
				(font
					(size 0.635 0.4064)
					(thickness 0.1524)
				)
				(justify left)
			)
		)
		(fp_text user "40"
			(at -3.2004 -3.096768 270)
			(unlocked yes)
			(layer "F.Fab")
			(effects
				(font
					(size 0.635 0.4064)
					(thickness 0.1524)
				)
				(justify left)
			)
		)
		(fp_text user "30"
			(at 3.223768 -3.0988 180)
			(unlocked yes)
			(layer "F.Fab")
			(effects
				(font
					(size 0.635 0.4064)
					(thickness 0.1524)
				)
				(justify left)
			)
		)
		(fp_text user "31"
			(at 1.8542 -3.172968 270)
			(unlocked yes)
			(layer "F.Fab")
			(effects
				(font
					(size 0.635 0.4064)
					(thickness 0.1524)
				)
				(justify left)
			)
		)
		(pad "1" smd rect
			(at -2.400046 -1.800098 180)
			(size 0.1778 0.6096)
			(layers "F.Cu" "F.Mask" "F.Paste")
			(net "NC_PVDD11_S3_P0_PWM8")
		)
		(pad "2" smd rect
			(at -2.400046 -1.400048 180)
			(size 0.1778 0.6096)
			(layers "F.Cu" "F.Mask" "F.Paste")
			(net "NC_PVDD11_S3_P0_PWM7")
		)
		(pad "3" smd rect
			(at -2.400046 -0.999998 180)
			(size 0.1778 0.6096)
			(layers "F.Cu" "F.Mask" "F.Paste")
			(net "NC_PVDD11_S3_P0_PWM6")
		)
		(pad "4" smd rect
			(at -2.400046 -0.599948 180)
			(size 0.1778 0.6096)
			(layers "F.Cu" "F.Mask" "F.Paste")
			(net "NC_PVDD11_S3_P0_PWM5")
		)
		(pad "5" smd rect
			(at -2.400046 -0.199898 180)
			(size 0.1778 0.6096)
			(layers "F.Cu" "F.Mask" "F.Paste")
			(net "NC_PVDD11_S3_P0_PWM4")
		)
		(pad "6" smd rect
			(at -2.400046 0.199898 180)
			(size 0.1778 0.6096)
			(layers "F.Cu" "F.Mask" "F.Paste")
			(net "NC_PVDD11_S3_P0_PWM3")
		)
		(pad "7" smd rect
			(at -2.400046 0.599948 180)
			(size 0.1778 0.6096)
			(layers "F.Cu" "F.Mask" "F.Paste")
			(net "PVDD11_S3_P0_PWM2")
		)
		(pad "8" smd rect
			(at -2.400046 0.999998 180)
			(size 0.1778 0.6096)
			(layers "F.Cu" "F.Mask" "F.Paste")
			(net "PVDD11_S3_P0_PWM1")
		)
		(pad "9" smd rect
			(at -2.400046 1.400048 180)
			(size 0.1778 0.6096)
			(layers "F.Cu" "F.Mask" "F.Paste")
			(net "PVDD11_S3_P0_PMSDA_R")
		)
		(pad "10" smd rect
			(at -2.400046 1.800098 180)
			(size 0.1778 0.6096)
			(layers "F.Cu" "F.Mask" "F.Paste")
			(net "PVDD11_S3_P0_PMSCL_R")
		)
		(pad "11" smd rect
			(at -1.800098 2.400046 270)
			(size 0.1778 0.6096)
			(layers "F.Cu" "F.Mask" "F.Paste")
			(net "PVDD11_S3_P0_PMALERT_R")
		)
		(pad "12" smd rect
			(at -1.400048 2.400046 270)
			(size 0.1778 0.6096)
			(layers "F.Cu" "F.Mask" "F.Paste")
			(net "PWRGD_PVDD11_S3_P0_R")
		)
		(pad "13" smd rect
			(at -0.999998 2.400046 270)
			(size 0.1778 0.6096)
			(layers "F.Cu" "F.Mask" "F.Paste")
			(net "PVDD11_S3_P0_EN_R")
		)
		(pad "14" smd rect
			(at -0.599948 2.400046 270)
			(size 0.1778 0.6096)
			(layers "F.Cu" "F.Mask" "F.Paste")
			(net "PVDD11_S3_P0_RESET_N_R")
		)
		(pad "15" smd rect
			(at -0.199898 2.400046 270)
			(size 0.1778 0.6096)
			(layers "F.Cu" "F.Mask" "F.Paste")
			(net "PVDD11_S3_P0_VDDIO")
		)
		(pad "16" smd rect
			(at 0.199898 2.400046 270)
			(size 0.1778 0.6096)
			(layers "F.Cu" "F.Mask" "F.Paste")
			(net "NC_PVDD11_S3_P0_PG1")
		)
		(pad "17" smd rect
			(at 0.599948 2.400046 270)
			(size 0.1778 0.6096)
			(layers "F.Cu" "F.Mask" "F.Paste")
			(net "GND")
		)
		(pad "18" smd rect
			(at 0.999998 2.400046 270)
			(size 0.1778 0.6096)
			(layers "F.Cu" "F.Mask" "F.Paste")
			(net "GND")
		)
		(pad "19" smd rect
			(at 1.400048 2.400046 270)
			(size 0.1778 0.6096)
			(layers "F.Cu" "F.Mask" "F.Paste")
			(net "NC_PVDD11_S3_P0_SVTO")
		)
		(pad "20" smd rect
			(at 1.800098 2.400046 270)
			(size 0.1778 0.6096)
			(layers "F.Cu" "F.Mask" "F.Paste")
			(net "GND")
		)
		(pad "21" smd rect
			(at 2.400046 1.800098 180)
			(size 0.1778 0.6096)
			(layers "F.Cu" "F.Mask" "F.Paste")
			(net "VSENSE_PVDD11_S3_P0_R")
		)
		(pad "22" smd rect
			(at 2.400046 1.400048 180)
			(size 0.1778 0.6096)
			(layers "F.Cu" "F.Mask" "F.Paste")
			(net "VSENSE_VSS_SENSE_C_P0")
		)
		(pad "23" smd rect
			(at 2.400046 0.999998 180)
			(size 0.1778 0.6096)
			(layers "F.Cu" "F.Mask" "F.Paste")
			(net "PVDD11_S3_P0_IMON1")
		)
		(pad "24" smd rect
			(at 2.400046 0.599948 180)
			(size 0.1778 0.6096)
			(layers "F.Cu" "F.Mask" "F.Paste")
			(net "PVDD11_S3_P0_IMON2")
		)
		(pad "25" smd rect
			(at 2.400046 0.199898 180)
			(size 0.1778 0.6096)
			(layers "F.Cu" "F.Mask" "F.Paste")
			(net "NC_PVDD11_S3_P0_IMON3")
		)
		(pad "26" smd rect
			(at 2.400046 -0.199898 180)
			(size 0.1778 0.6096)
			(layers "F.Cu" "F.Mask" "F.Paste")
			(net "NC_PVDD11_S3_P0_IMON4")
		)
		(pad "27" smd rect
			(at 2.400046 -0.599948 180)
			(size 0.1778 0.6096)
			(layers "F.Cu" "F.Mask" "F.Paste")
			(net "NC_PVDD11_S3_P0_IMON5")
		)
		(pad "28" smd rect
			(at 2.400046 -0.999998 180)
			(size 0.1778 0.6096)
			(layers "F.Cu" "F.Mask" "F.Paste")
			(net "NC_PVDD11_S3_P0_IMON6")
		)
		(pad "29" smd rect
			(at 2.400046 -1.400048 180)
			(size 0.1778 0.6096)
			(layers "F.Cu" "F.Mask" "F.Paste")
			(net "NC_PVDD11_S3_P0_IMON7")
		)
		(pad "30" smd rect
			(at 2.400046 -1.800098 180)
			(size 0.1778 0.6096)
			(layers "F.Cu" "F.Mask" "F.Paste")
			(net "NC_PVDD11_S3_P0_IMON8")
		)
		(pad "31" smd rect
			(at 1.800098 -2.400046 270)
			(size 0.1778 0.6096)
			(layers "F.Cu" "F.Mask" "F.Paste")
			(net "GND")
		)
		(pad "32" smd rect
			(at 1.400048 -2.400046 270)
			(size 0.1778 0.6096)
			(layers "F.Cu" "F.Mask" "F.Paste")
			(net "GND")
		)
		(pad "33" smd rect
			(at 0.999998 -2.400046 270)
			(size 0.1778 0.6096)
			(layers "F.Cu" "F.Mask" "F.Paste")
			(net "PVDD11_S3_P0_OCP_N_R")
		)
		(pad "34" smd rect
			(at 0.599948 -2.400046 270)
			(size 0.1778 0.6096)
			(layers "F.Cu" "F.Mask" "F.Paste")
			(net "PVDD11_S3_P0_ADDR_CFG")
		)
		(pad "35" smd rect
			(at 0.199898 -2.400046 270)
			(size 0.1778 0.6096)
			(layers "F.Cu" "F.Mask" "F.Paste")
			(net "PVDD11_S3_P0_TEMP1")
		)
		(pad "36" smd rect
			(at -0.199898 -2.400046 270)
			(size 0.1778 0.6096)
			(layers "F.Cu" "F.Mask" "F.Paste")
			(net "PVDD11_S3_P0_TEMP0")
		)
		(pad "37" smd rect
			(at -0.599948 -2.400046 270)
			(size 0.1778 0.6096)
			(layers "F.Cu" "F.Mask" "F.Paste")
			(net "PVDD11_S3_P0_VMON")
		)
		(pad "38" smd rect
			(at -0.999998 -2.400046 270)
			(size 0.1778 0.6096)
			(layers "F.Cu" "F.Mask" "F.Paste")
			(net "PVDD11_S3_P0_VINSEN")
		)
		(pad "39" smd rect
			(at -1.400048 -2.400046 270)
			(size 0.1778 0.6096)
			(layers "F.Cu" "F.Mask" "F.Paste")
			(net "PVDD11_S3_P0_VCC")
		)
		(pad "40" smd rect
			(at -1.800098 -2.400046 270)
			(size 0.1778 0.6096)
			(layers "F.Cu" "F.Mask" "F.Paste")
			(net "PVDD11_S3_P0_VCCS")
		)
		(pad "TH" smd rect
			(at 0 0 270)
			(size 3.6576 3.6576)
			(layers "F.Cu" "F.Mask" "F.Paste")
			(net "GND")
		)
		(zone
			(layer "F.Cu")
			(hatch none 0.5)
			(connect_pads
				(clearance 0)
			)
			(min_thickness 0.25)
			(keepout
				(tracks not_allowed)
				(vias allowed)
				(pads allowed)
				(copperpour not_allowed)
				(footprints allowed)
			)
			(placement
				(enabled no)
				(sheetname "")
			)
			(fill
				(thermal_gap 0.5)
				(thermal_bridge_width 0.5)
				(island_removal_mode 0)
			)
			(polygon
				(pts
					(xy 416.885882 -361.70362) (xy 416.885882 -364.119414) (xy 420.772082 -364.119414) (xy 420.772082 -363.967014)
					(xy 417.038282 -363.967014) (xy 417.038282 -361.70362)
				)
			)
		)
	)
	(footprint ""
		(layer "F.Cu")
		(at 402.151088 -330.778612)
		(property "Reference" "R940"
			(at 0 0 0)
			(layer "F.SilkS")
			(hide yes)
			(effects
				(font
					(size 1.27 1.27)
				)
			)
		)
		(property "Value" ""
			(at 0 0 0)
			(layer "F.Fab")
			(effects
				(font
					(size 1.27 1.27)
				)
			)
		)
		(duplicate_pad_numbers_are_jumpers no)
		(fp_line
			(start -0.7874 -0.4064)
			(end 0.7874 -0.4064)
			(stroke
				(width 0.1524)
				(type default)
			)
			(layer "F.SilkS")
		)
		(fp_line
			(start -0.7874 0.4064)
			(end -0.7874 -0.4064)
			(stroke
				(width 0.1524)
				(type default)
			)
			(layer "F.SilkS")
		)
		(fp_line
			(start 0.7874 -0.4064)
			(end 0.7874 0.4064)
			(stroke
				(width 0.1524)
				(type default)
			)
			(layer "F.SilkS")
		)
		(fp_line
			(start 0.7874 0.4064)
			(end -0.7874 0.4064)
			(stroke
				(width 0.1524)
				(type default)
			)
			(layer "F.SilkS")
		)
		(fp_line
			(start -0.67945 -0.305054)
			(end -0.12065 -0.305054)
			(stroke
				(width 0.1)
				(type default)
			)
			(layer "F.Fab")
		)
		(fp_line
			(start -0.67945 0.3048)
			(end -0.67945 -0.305054)
			(stroke
				(width 0.1)
				(type default)
			)
			(layer "F.Fab")
		)
		(fp_line
			(start -0.12065 -0.305054)
			(end -0.12065 -0.2794)
			(stroke
				(width 0.1)
				(type default)
			)
			(layer "F.Fab")
		)
		(fp_line
			(start -0.12065 -0.2794)
			(end 0.12065 -0.2794)
			(stroke
				(width 0.1)
				(type default)
			)
			(layer "F.Fab")
		)
		(fp_line
			(start -0.12065 0.2794)
			(end -0.12065 0.3048)
			(stroke
				(width 0.1)
				(type default)
			)
			(layer "F.Fab")
		)
		(fp_line
			(start -0.12065 0.3048)
			(end -0.67945 0.3048)
			(stroke
				(width 0.1)
				(type default)
			)
			(layer "F.Fab")
		)
		(fp_line
			(start 0.120396 0.2794)
			(end -0.12065 0.2794)
			(stroke
				(width 0.1)
				(type default)
			)
			(layer "F.Fab")
		)
		(fp_line
			(start 0.120396 0.3048)
			(end 0.120396 0.2794)
			(stroke
				(width 0.1)
				(type default)
			)
			(layer "F.Fab")
		)
		(fp_line
			(start 0.12065 -0.3048)
			(end 0.67945 -0.3048)
			(stroke
				(width 0.1)
				(type default)
			)
			(layer "F.Fab")
		)
		(fp_line
			(start 0.12065 -0.2794)
			(end 0.12065 -0.3048)
			(stroke
				(width 0.1)
				(type default)
			)
			(layer "F.Fab")
		)
		(fp_line
			(start 0.67945 -0.3048)
			(end 0.67945 0.3048)
			(stroke
				(width 0.1)
				(type default)
			)
			(layer "F.Fab")
		)
		(fp_line
			(start 0.67945 0.3048)
			(end 0.120396 0.3048)
			(stroke
				(width 0.1)
				(type default)
			)
			(layer "F.Fab")
		)
		(pad "1" smd circle
			(at -0.40005 0)
			(size 0 0)
			(layers "F.Cu" "F.Mask" "F.Paste")
			(net "BOOT_RDY_R_H")
		)
		(pad "2" smd circle
			(at 0.40005 0)
			(size 0 0)
			(layers "F.Cu" "F.Mask" "F.Paste")
			(net "BOOT_RDY_H")
		)
	)
)
